(kicad_pcb
	(version 20260206)
	(generator "pcbnew")
	(generator_version "10.0")
	(general
		(thickness 1.6)
		(legacy_teardrops no)
	)
	(paper "A4")
	(title_block
		(title "04192023_DAF0TMB3IC0_F0TG_MB_C_brd_V02_OCP.brd")
		(comment 1 "Grand Teton / footprint 2165 of 8354 (J20), pads 227-291 of 291")
	)
	(layers
		(0 "F.Cu" signal "TOP")
		(4 "In1.Cu" signal "GND")
		(6 "In2.Cu" signal "IN1")
		(8 "In3.Cu" signal "GND1")
		(10 "In4.Cu" signal "IN2")
		(12 "In5.Cu" signal "GND2")
		(14 "In6.Cu" signal "IN3")
		(16 "In7.Cu" signal "GND3")
		(18 "In8.Cu" signal "VCC")
		(20 "In9.Cu" signal "VCC1")
		(22 "In10.Cu" signal "GND4")
		(24 "In11.Cu" signal "IN4")
		(26 "In12.Cu" signal "GND5")
		(28 "In13.Cu" signal "IN5")
		(30 "In14.Cu" signal "GND6")
		(32 "In15.Cu" signal "IN6")
		(34 "In16.Cu" signal "GND7")
		(2 "B.Cu" signal "BOTTOM")
		(9 "F.Adhes" user "F.Adhesive")
		(11 "B.Adhes" user "B.Adhesive")
		(13 "F.Paste" user "Package Geometry/Pastemask Top")
		(15 "B.Paste" user "Package Geometry/Pastemask Bottom")
		(5 "F.SilkS" user "Ref Des/Silkscreen Top")
		(7 "B.SilkS" user "Ref Des/Silkscreen Bottom")
		(1 "F.Mask" user "Board Geometry/Soldermask Top")
		(3 "B.Mask" user "Board Geometry/Soldermask Bottom")
		(17 "Dwgs.User" user "User.Drawings")
		(19 "Cmts.User" user "User.Comments")
		(21 "Eco1.User" user "User.Eco1")
		(23 "Eco2.User" user "User.Eco2")
		(25 "Edge.Cuts" user "Board Geometry/Outline")
		(27 "Margin" user)
		(31 "F.CrtYd" user "Package Geometry/Place Bound Top")
		(29 "B.CrtYd" user "Package Geometry/Place Bound Bottom")
		(35 "F.Fab" user "Ref Des/Assembly Top")
		(33 "B.Fab" user "Ref Des/Assembly Bottom")
	)
	(footprint ""
		(layer "F.Cu")
		(at 444.594234 -255.560068 180)
		(property "Reference" "J20"
			(at 1.631188 -81.796128 0)
			(unlocked yes)
			(layer "F.SilkS")
			(effects
				(font
					(size 0.7874 0.5842)
					(thickness 0.1524)
				)
			)
		)
		(property "Value" ""
			(at 0 0 180)
			(layer "F.Fab")
			(effects
				(font
					(size 1.27 1.27)
				)
			)
		)
		(duplicate_pad_numbers_are_jumpers no)
		(pad "227" smd rect
			(at 2.050034 11.474958 90)
			(size 0.519938 1.4986)
			(layers "F.Cu" "F.Mask" "F.Paste")
			(net "M_K_CPU0_SB_PAR")
		)
		(pad "228" smd rect
			(at 2.050034 12.325096 90)
			(size 0.519938 1.4986)
			(layers "F.Cu" "F.Mask" "F.Paste")
			(net "GND")
		)
		(pad "229" smd rect
			(at 2.050034 13.17498 90)
			(size 0.519938 1.4986)
			(layers "F.Cu" "F.Mask" "F.Paste")
			(net "M_K_CPU0_SB_CS_N<1>")
		)
		(pad "230" smd rect
			(at 2.050034 14.025118 90)
			(size 0.519938 1.4986)
			(layers "F.Cu" "F.Mask" "F.Paste")
			(net "GND")
		)
		(pad "231" smd rect
			(at 2.050034 14.875002 90)
			(size 0.519938 1.4986)
			(layers "F.Cu" "F.Mask" "F.Paste")
			(net "Net_2394")
		)
		(pad "232" smd rect
			(at 2.050034 15.724886 90)
			(size 0.519938 1.4986)
			(layers "F.Cu" "F.Mask" "F.Paste")
			(net "Net_2395")
		)
		(pad "233" smd rect
			(at 2.050034 16.575024 90)
			(size 0.519938 1.4986)
			(layers "F.Cu" "F.Mask" "F.Paste")
			(net "GND")
		)
		(pad "234" smd rect
			(at 2.050034 17.424908 90)
			(size 0.519938 1.4986)
			(layers "F.Cu" "F.Mask" "F.Paste")
			(net "M_K_CPU0_SB_CB<6>")
		)
		(pad "235" smd rect
			(at 2.050034 18.275046 90)
			(size 0.519938 1.4986)
			(layers "F.Cu" "F.Mask" "F.Paste")
			(net "GND")
		)
		(pad "236" smd rect
			(at 2.050034 19.12493 90)
			(size 0.519938 1.4986)
			(layers "F.Cu" "F.Mask" "F.Paste")
			(net "M_K_CPU0_SB_CB<7>")
		)
		(pad "237" smd rect
			(at 2.050034 19.975068 90)
			(size 0.519938 1.4986)
			(layers "F.Cu" "F.Mask" "F.Paste")
			(net "GND")
		)
		(pad "238" smd rect
			(at 2.050034 20.824952 90)
			(size 0.519938 1.4986)
			(layers "F.Cu" "F.Mask" "F.Paste")
			(net "M_K_CPU0_SB_DQS_DN<4>")
		)
		(pad "239" smd rect
			(at 2.050034 21.67509 90)
			(size 0.519938 1.4986)
			(layers "F.Cu" "F.Mask" "F.Paste")
			(net "M_K_CPU0_SB_DQS_DP<4>")
		)
		(pad "240" smd rect
			(at 2.050034 22.524974 90)
			(size 0.519938 1.4986)
			(layers "F.Cu" "F.Mask" "F.Paste")
			(net "GND")
		)
		(pad "241" smd rect
			(at 2.050034 23.375112 90)
			(size 0.519938 1.4986)
			(layers "F.Cu" "F.Mask" "F.Paste")
			(net "M_K_CPU0_SB_CB<2>")
		)
		(pad "242" smd rect
			(at 2.050034 24.224996 90)
			(size 0.519938 1.4986)
			(layers "F.Cu" "F.Mask" "F.Paste")
			(net "GND")
		)
		(pad "243" smd rect
			(at 2.050034 25.07488 90)
			(size 0.519938 1.4986)
			(layers "F.Cu" "F.Mask" "F.Paste")
			(net "M_K_CPU0_SB_CB<3>")
		)
		(pad "244" smd rect
			(at 2.050034 25.925018 90)
			(size 0.519938 1.4986)
			(layers "F.Cu" "F.Mask" "F.Paste")
			(net "GND")
		)
		(pad "245" smd rect
			(at 2.050034 26.774902 90)
			(size 0.519938 1.4986)
			(layers "F.Cu" "F.Mask" "F.Paste")
			(net "M_K_CPU0_SB_DQ<2>")
		)
		(pad "246" smd rect
			(at 2.050034 27.62504 90)
			(size 0.519938 1.4986)
			(layers "F.Cu" "F.Mask" "F.Paste")
			(net "GND")
		)
		(pad "247" smd rect
			(at 2.050034 28.474924 90)
			(size 0.519938 1.4986)
			(layers "F.Cu" "F.Mask" "F.Paste")
			(net "M_K_CPU0_SB_DQ<3>")
		)
		(pad "248" smd rect
			(at 2.050034 29.325062 90)
			(size 0.519938 1.4986)
			(layers "F.Cu" "F.Mask" "F.Paste")
			(net "GND")
		)
		(pad "249" smd rect
			(at 2.050034 30.174946 90)
			(size 0.519938 1.4986)
			(layers "F.Cu" "F.Mask" "F.Paste")
			(net "M_K_CPU0_SB_DQS_DN<5>")
		)
		(pad "250" smd rect
			(at 2.050034 31.025084 90)
			(size 0.519938 1.4986)
			(layers "F.Cu" "F.Mask" "F.Paste")
			(net "M_K_CPU0_SB_DQS_DP<5>")
		)
		(pad "251" smd rect
			(at 2.050034 31.874968 90)
			(size 0.519938 1.4986)
			(layers "F.Cu" "F.Mask" "F.Paste")
			(net "GND")
		)
		(pad "252" smd rect
			(at 2.050034 32.725106 90)
			(size 0.519938 1.4986)
			(layers "F.Cu" "F.Mask" "F.Paste")
			(net "M_K_CPU0_SB_DQ<6>")
		)
		(pad "253" smd rect
			(at 2.050034 33.57499 90)
			(size 0.519938 1.4986)
			(layers "F.Cu" "F.Mask" "F.Paste")
			(net "GND")
		)
		(pad "254" smd rect
			(at 2.050034 34.425128 90)
			(size 0.519938 1.4986)
			(layers "F.Cu" "F.Mask" "F.Paste")
			(net "M_K_CPU0_SB_DQ<7>")
		)
		(pad "255" smd rect
			(at 2.050034 35.275012 90)
			(size 0.519938 1.4986)
			(layers "F.Cu" "F.Mask" "F.Paste")
			(net "GND")
		)
		(pad "256" smd rect
			(at 2.050034 36.124896 90)
			(size 0.519938 1.4986)
			(layers "F.Cu" "F.Mask" "F.Paste")
			(net "M_K_CPU0_SB_DQ<10>")
		)
		(pad "257" smd rect
			(at 2.050034 36.975034 90)
			(size 0.519938 1.4986)
			(layers "F.Cu" "F.Mask" "F.Paste")
			(net "GND")
		)
		(pad "258" smd rect
			(at 2.050034 37.824918 90)
			(size 0.519938 1.4986)
			(layers "F.Cu" "F.Mask" "F.Paste")
			(net "M_K_CPU0_SB_DQ<11>")
		)
		(pad "259" smd rect
			(at 2.050034 38.675056 90)
			(size 0.519938 1.4986)
			(layers "F.Cu" "F.Mask" "F.Paste")
			(net "GND")
		)
		(pad "260" smd rect
			(at 2.050034 39.52494 90)
			(size 0.519938 1.4986)
			(layers "F.Cu" "F.Mask" "F.Paste")
			(net "M_K_CPU0_SB_DQS_DN<6>")
		)
		(pad "261" smd rect
			(at 2.050034 40.375078 90)
			(size 0.519938 1.4986)
			(layers "F.Cu" "F.Mask" "F.Paste")
			(net "M_K_CPU0_SB_DQS_DP<6>")
		)
		(pad "262" smd rect
			(at 2.050034 41.224962 90)
			(size 0.519938 1.4986)
			(layers "F.Cu" "F.Mask" "F.Paste")
			(net "GND")
		)
		(pad "263" smd rect
			(at 2.050034 42.0751 90)
			(size 0.519938 1.4986)
			(layers "F.Cu" "F.Mask" "F.Paste")
			(net "M_K_CPU0_SB_DQ<14>")
		)
		(pad "264" smd rect
			(at 2.050034 42.924984 90)
			(size 0.519938 1.4986)
			(layers "F.Cu" "F.Mask" "F.Paste")
			(net "GND")
		)
		(pad "265" smd rect
			(at 2.050034 43.775122 90)
			(size 0.519938 1.4986)
			(layers "F.Cu" "F.Mask" "F.Paste")
			(net "M_K_CPU0_SB_DQ<15>")
		)
		(pad "266" smd rect
			(at 2.050034 44.625006 90)
			(size 0.519938 1.4986)
			(layers "F.Cu" "F.Mask" "F.Paste")
			(net "GND")
		)
		(pad "267" smd rect
			(at 2.050034 45.47489 90)
			(size 0.519938 1.4986)
			(layers "F.Cu" "F.Mask" "F.Paste")
			(net "M_K_CPU0_SB_DQ<18>")
		)
		(pad "268" smd rect
			(at 2.050034 46.325028 90)
			(size 0.519938 1.4986)
			(layers "F.Cu" "F.Mask" "F.Paste")
			(net "GND")
		)
		(pad "269" smd rect
			(at 2.050034 47.174912 90)
			(size 0.519938 1.4986)
			(layers "F.Cu" "F.Mask" "F.Paste")
			(net "M_K_CPU0_SB_DQ<19>")
		)
		(pad "270" smd rect
			(at 2.050034 48.02505 90)
			(size 0.519938 1.4986)
			(layers "F.Cu" "F.Mask" "F.Paste")
			(net "GND")
		)
		(pad "271" smd rect
			(at 2.050034 48.874934 90)
			(size 0.519938 1.4986)
			(layers "F.Cu" "F.Mask" "F.Paste")
			(net "M_K_CPU0_SB_DQS_DN<7>")
		)
		(pad "272" smd rect
			(at 2.050034 49.725072 90)
			(size 0.519938 1.4986)
			(layers "F.Cu" "F.Mask" "F.Paste")
			(net "M_K_CPU0_SB_DQS_DP<7>")
		)
		(pad "273" smd rect
			(at 2.050034 50.574956 90)
			(size 0.519938 1.4986)
			(layers "F.Cu" "F.Mask" "F.Paste")
			(net "GND")
		)
		(pad "274" smd rect
			(at 2.050034 51.425094 90)
			(size 0.519938 1.4986)
			(layers "F.Cu" "F.Mask" "F.Paste")
			(net "M_K_CPU0_SB_DQ<22>")
		)
		(pad "275" smd rect
			(at 2.050034 52.274978 90)
			(size 0.519938 1.4986)
			(layers "F.Cu" "F.Mask" "F.Paste")
			(net "GND")
		)
		(pad "276" smd rect
			(at 2.050034 53.125116 90)
			(size 0.519938 1.4986)
			(layers "F.Cu" "F.Mask" "F.Paste")
			(net "M_K_CPU0_SB_DQ<23>")
		)
		(pad "277" smd rect
			(at 2.050034 53.975 90)
			(size 0.519938 1.4986)
			(layers "F.Cu" "F.Mask" "F.Paste")
			(net "GND")
		)
		(pad "278" smd rect
			(at 2.050034 54.824884 90)
			(size 0.519938 1.4986)
			(layers "F.Cu" "F.Mask" "F.Paste")
			(net "M_K_CPU0_SB_DQ<26>")
		)
		(pad "279" smd rect
			(at 2.050034 55.675022 90)
			(size 0.519938 1.4986)
			(layers "F.Cu" "F.Mask" "F.Paste")
			(net "GND")
		)
		(pad "280" smd rect
			(at 2.050034 56.524906 90)
			(size 0.519938 1.4986)
			(layers "F.Cu" "F.Mask" "F.Paste")
			(net "M_K_CPU0_SB_DQ<27>")
		)
		(pad "281" smd rect
			(at 2.050034 57.375044 90)
			(size 0.519938 1.4986)
			(layers "F.Cu" "F.Mask" "F.Paste")
			(net "GND")
		)
		(pad "282" smd rect
			(at 2.050034 58.224928 90)
			(size 0.519938 1.4986)
			(layers "F.Cu" "F.Mask" "F.Paste")
			(net "M_K_CPU0_SB_DQS_DN<8>")
		)
		(pad "283" smd rect
			(at 2.050034 59.075066 90)
			(size 0.519938 1.4986)
			(layers "F.Cu" "F.Mask" "F.Paste")
			(net "M_K_CPU0_SB_DQS_DP<8>")
		)
		(pad "284" smd rect
			(at 2.050034 59.92495 90)
			(size 0.519938 1.4986)
			(layers "F.Cu" "F.Mask" "F.Paste")
			(net "GND")
		)
		(pad "285" smd rect
			(at 2.050034 60.775088 90)
			(size 0.519938 1.4986)
			(layers "F.Cu" "F.Mask" "F.Paste")
			(net "M_K_CPU0_SB_DQ<30>")
		)
		(pad "286" smd rect
			(at 2.050034 61.624972 90)
			(size 0.519938 1.4986)
			(layers "F.Cu" "F.Mask" "F.Paste")
			(net "GND")
		)
		(pad "287" smd rect
			(at 2.050034 62.47511 90)
			(size 0.519938 1.4986)
			(layers "F.Cu" "F.Mask" "F.Paste")
			(net "M_K_CPU0_SB_DQ<31>")
		)
		(pad "288" smd rect
			(at 2.050034 63.324994 90)
			(size 0.519938 1.4986)
			(layers "F.Cu" "F.Mask" "F.Paste")
			(net "GND")
		)
		(pad "G1" thru_hole oval
			(at 0 -68.97497 90)
			(size 1.7272 3.4798)
			(drill oval 1.2192 2.4638)
			(layers "*.Cu" "*.Mask")
			(remove_unused_layers no)
			(net "GND")
			(clearance 0.127)
			(thermal_gap 0.127)
		)
		(pad "G2" thru_hole oval
			(at 0 3.875024 90)
			(size 1.7272 3.4798)
			(drill oval 1.2192 2.4638)
			(layers "*.Cu" "*.Mask")
			(remove_unused_layers no)
			(net "GND")
			(clearance 0.127)
			(thermal_gap 0.127)
		)
		(pad "G3" thru_hole oval
			(at 0 68.97497 90)
			(size 1.7272 3.4798)
			(drill oval 1.2192 2.4638)
			(layers "*.Cu" "*.Mask")
			(remove_unused_layers no)
			(net "GND")
			(clearance 0.127)
			(thermal_gap 0.127)
		)
	)
)
